#ISCELL
  pure_quanta quanta_title_block_c *
  *
#ISCELL
  standard offpage *
  page46_i1
#ISCELL
  standard offpage *
  page46_i10
#ISCELL
  standard offpage *
  page46_i11
#ISCELL
  standard offpage *
  page46_i12
#ISCELL
  standard offpage *
  page46_i13
#ISCELL
  standard offpage *
  page46_i14
#ISCELL
  standard offpage *
  page46_i15
#ISCELL
  standard offpage *
  page46_i16
#ISCELL
  standard offpage *
  page46_i17
#ISCELL
  standard offpage *
  page46_i18
#ISCELL
  standard offpage *
  page46_i2
#ISCELL
  standard offpage *
  page46_i26
#ISCELL
  standard offpage *
  page46_i37
#ISCELL
  standard offpage *
  page46_i4
#CELL
  pure_quanta socket4677_azif0045p001c01cs *
  page46_i5
